FILE_TYPE = MACRO_DRAWING;
SET COLOR_WIRE YELLOW;
SET COLOR_PROP ORANGE;
SET COLOR_DOT WHITE;
SET COLOR_ARC YELLOW;
SET COLOR_BODY GREEN;
SET COLOR_NOTE PURPLE;
SET PROP_DISPLAY VALUE;
SET PAGE_NUMBER P64;
FORCEADD QUANTA_TITLE_BLOCK_C..1
(0 0);
FORCEPROP 1 LAST CUSTOM_TXT_CDS <NAME_2>
J 0
(-3175 50);
FORCEPROP 1 LAST CUSTOM_TXT_CDS <NAME_1>
J 0
(-3175 175);
FORCEPROP 1 LAST CUSTOM_TXT_CDS <Q_NUMBER>
J 0
(-1403 103);
DISPLAY 1.212766 (-1403 103);
FORCEPROP 1 LAST CUSTOM_TXT_CDS <Q_PROJ>
J 0
(-2382 102);
DISPLAY 1.212766 (-2382 102);
FORCEPROP 1 LAST CUSTOM_TXT_CDS <Q_REV>
J 0
(-184 103);
DISPLAY 1.212766 (-184 103);
FORCEPROP 1 LAST CUSTOM_TXT_CDS <CON_LAST_MODIFIED>
J 0
(-1885 15);
DISPLAY 0.978723 (-1885 15);
FORCEPROP 1 LAST CUSTOM_TXT_CDS <CON_PAGE_NUM> OF <CON_TOTAL_PAGES>
J 0
(-446 18);
DISPLAY 0.978723 (-446 18);
FORCEPROP 1 LAST Q_DEPT BU9
J 1
(-3763 49);
DISPLAY 1.957447 (-3763 49);
PAINT GREEN (-3763 49);
FORCEPROP 1 LAST Q_TITLE AC CAPS CPU0 P2/P3 TX
J 0
(-9275 50);
DISPLAY 2.446809 (-9275 50);
PAINT GREEN (-9275 50);
FORCEPROP 2 LAST PAGE_BORDER TRUE
J 0
(-7890 5250);
DISPLAY 0.638298 (-7890 5250);
PAINT PINK (-7890 5250);
DISPLAY INVISIBLE (-7890 5250);
FORCEPROP 1 LAST CDS_LMAN_SYM_OUTLINE -9475,6775,100,-125
J 0
(0 0);
DISPLAY 0.468085 (0 0);
PAINT GREEN (0 0);
DISPLAY INVISIBLE (0 0);
FORCEPROP 2 LAST CDS_LIB pure_quanta
J 0
(0 0);
DISPLAY INVISIBLE (0 0);
FORCEPROP 1 LAST COMMENT_BODY TRUE
J 0
(12 -13);
DISPLAY 0.978723 (12 -13);
PAINT GREEN (12 -13);
DISPLAY INVISIBLE (12 -13);
FORCEPROP 2 LAST CDS_XR_PAGE_TITLE CR-64 : @T6G_MB_LIB.T6G(SCH_1):PAGE64
J 0
(-7890 5250);
DISPLAY 0.638298 (-7890 5250);
PAINT PINK (-7890 5250);
DISPLAY INVISIBLE (-7890 5250);
FORCEPROP 2 LAST CUSTOM_TXT_CDS <XR_PAGE_TITLE>
J 0
(-7890 5250);
DISPLAY 0.638298 (-7890 5250);
PAINT PINK (-7890 5250);
DISPLAY INVISIBLE (-7890 5250);
FORCEPROP 0 LAST CDS_CON_LAST_MODIFIED Thu Mar 10 20:15:14 2022
J 0
(-1885 15);
DISPLAY INVISIBLE (-1885 15);
QUIT
